FILE_TYPE=LIBRARY_PARTS;
TIME=' COMPILATION ON MON JUL 05 19:34:43 2010  ';
PRIMITIVE 'IDTQS3VH257PAG';
  PIN
    'YA':
      PIN_NUMBER='(4)';
      INPUT_LOAD='(-0.01,0.01)';
      OUTPUT_LOAD='(1.0,-1.0)';
      BIDIRECTIONAL='TRUE';
    'YB':
      PIN_NUMBER='(7)';
      INPUT_LOAD='(-0.01,0.01)';
      OUTPUT_LOAD='(1.0,-1.0)';
      BIDIRECTIONAL='TRUE';
    'YC':
      PIN_NUMBER='(9)';
      INPUT_LOAD='(-0.01,0.01)';
      OUTPUT_LOAD='(1.0,-1.0)';
      BIDIRECTIONAL='TRUE';
    'YD':
      PIN_NUMBER='(12)';
      INPUT_LOAD='(-0.01,0.01)';
      OUTPUT_LOAD='(1.0,-1.0)';
      BIDIRECTIONAL='TRUE';
    'S':
      PIN_NUMBER='(1)';
      INPUT_LOAD='(-0.01,0.01)';
    '-E':
      PIN_NUMBER='(15)';
      INPUT_LOAD='(-0.01,0.01)';
    'I_0A':
      PIN_NUMBER='(2)';
      INPUT_LOAD='(-0.01,0.01)';
      OUTPUT_LOAD='(1.0,-1.0)';
      BIDIRECTIONAL='TRUE';
    'I_1A':
      PIN_NUMBER='(3)';
      INPUT_LOAD='(-0.01,0.01)';
      OUTPUT_LOAD='(1.0,-1.0)';
      BIDIRECTIONAL='TRUE';
    'I_1B':
      PIN_NUMBER='(6)';
      INPUT_LOAD='(-0.01,0.01)';
      OUTPUT_LOAD='(1.0,-1.0)';
      BIDIRECTIONAL='TRUE';
    'I_0B':
      PIN_NUMBER='(5)';
      INPUT_LOAD='(-0.01,0.01)';
      OUTPUT_LOAD='(1.0,-1.0)';
      BIDIRECTIONAL='TRUE';
    'I_1C':
      PIN_NUMBER='(10)';
      INPUT_LOAD='(-0.01,0.01)';
      OUTPUT_LOAD='(1.0,-1.0)';
      BIDIRECTIONAL='TRUE';
    'I_0C':
      PIN_NUMBER='(11)';
      INPUT_LOAD='(-0.01,0.01)';
      OUTPUT_LOAD='(1.0,-1.0)';
      BIDIRECTIONAL='TRUE';
    'I_0D':
      PIN_NUMBER='(14)';
      INPUT_LOAD='(-0.01,0.01)';
      OUTPUT_LOAD='(1.0,-1.0)';
      BIDIRECTIONAL='TRUE';
    'I_1D':
      PIN_NUMBER='(13)';
      INPUT_LOAD='(-0.01,0.01)';
      OUTPUT_LOAD='(1.0,-1.0)';
      BIDIRECTIONAL='TRUE';
    'GND':
      PIN_NUMBER='(8)';
      PINUSE='POWER';
    'VCC':
      PIN_NUMBER='(16)';
      PINUSE='POWER';
  END_PIN;
  BODY
    PHYS_DES_PREFIX='U';
    CLASS='IC';
    PART_NAME='IDTQS3VH257PAG';
    BODY_NAME='idtqs3vh257pag';
  END_BODY;
END_PRIMITIVE;
END.
